# SCM (Grand Teton) — schematic netlist excerpt (pin names and nets, part order shuffled) for the footprints in the layout excerpt that follows; sources: Cadence DE-HDL packaged netlist, KiCad conversion of 12092022_DA0F0TMDCD0_F0T_Management_Board_D_brd_V3_OCP.brd

R67  Q_RES  4.7K 1% CHIP  pkg 0402LF  page 30 : A = P3V3_AUX ; B = UART_BMC_5_TXD_BUF1_R
C155  Q_CAP  0.001UF 50V 10% EMPTY  pkg C0402  page 55 : A = PWRGD_P1V2_AUX_R ; B = GND

(kicad_pcb
	(version 20260206)
	(generator "pcbnew")
	(generator_version "10.0")
	(general
		(thickness 1.6)
		(legacy_teardrops no)
	)
	(paper "A4")
	(title_block
		(title "12092022_DA0F0TMDCD0_F0T_Management_Board_D_brd_V3_OCP.brd")
		(comment 1 "Grand Teton / footprints 499-500 of 1440")
	)
	(layers
		(0 "F.Cu" signal "TOP")
		(4 "In1.Cu" signal "GND")
		(6 "In2.Cu" signal "IN1")
		(8 "In3.Cu" signal "GND1")
		(10 "In4.Cu" signal "IN2")
		(12 "In5.Cu" signal "VCC")
		(14 "In6.Cu" signal "VCC1")
		(16 "In7.Cu" signal "IN3")
		(18 "In8.Cu" signal "GND2")
		(20 "In9.Cu" signal "IN4")
		(22 "In10.Cu" signal "GND3")
		(2 "B.Cu" signal "BOTTOM")
		(9 "F.Adhes" user "F.Adhesive")
		(11 "B.Adhes" user "B.Adhesive")
		(13 "F.Paste" user "Package Geometry/Pastemask Top")
		(15 "B.Paste" user "Package Geometry/Pastemask Bottom")
		(5 "F.SilkS" user "Ref Des/Silkscreen Top")
		(7 "B.SilkS" user "Ref Des/Silkscreen Bottom")
		(1 "F.Mask" user "Board Geometry/Soldermask Top")
		(3 "B.Mask" user "Board Geometry/Soldermask Bottom")
		(17 "Dwgs.User" user "User.Drawings")
		(19 "Cmts.User" user "User.Comments")
		(21 "Eco1.User" user "User.Eco1")
		(23 "Eco2.User" user "User.Eco2")
		(25 "Edge.Cuts" user "Board Geometry/Outline")
		(27 "Margin" user)
		(31 "F.CrtYd" user "Package Geometry/Place Bound Top")
		(29 "B.CrtYd" user "Package Geometry/Place Bound Bottom")
		(35 "F.Fab" user "Ref Des/Assembly Top")
		(33 "B.Fab" user "Ref Des/Assembly Bottom")
	)
	(footprint ""
		(layer "F.Cu")
		(at 28.1432 -65.7098 90)
		(property "Reference" "R67"
			(at 0 0 90)
			(layer "F.SilkS")
			(hide yes)
			(effects
				(font
					(size 1.27 1.27)
				)
			)
		)
		(property "Value" ""
			(at 0 0 90)
			(layer "F.Fab")
			(effects
				(font
					(size 1.27 1.27)
				)
			)
		)
		(duplicate_pad_numbers_are_jumpers no)
		(fp_line
			(start 0.7874 -0.4064)
			(end 0.7874 0.4064)
			(stroke
				(width 0.1524)
				(type default)
			)
			(layer "F.SilkS")
		)
		(fp_line
			(start -0.7874 -0.4064)
			(end 0.7874 -0.4064)
			(stroke
				(width 0.1524)
				(type default)
			)
			(layer "F.SilkS")
		)
		(fp_line
			(start 0.7874 0.4064)
			(end -0.7874 0.4064)
			(stroke
				(width 0.1524)
				(type default)
			)
			(layer "F.SilkS")
		)
		(fp_line
			(start -0.7874 0.4064)
			(end -0.7874 -0.4064)
			(stroke
				(width 0.1524)
				(type default)
			)
			(layer "F.SilkS")
		)
		(fp_line
			(start -0.12065 -0.305054)
			(end -0.12065 -0.2794)
			(stroke
				(width 0.1)
				(type default)
			)
			(layer "F.Fab")
		)
		(fp_line
			(start -0.67945 -0.305054)
			(end -0.12065 -0.305054)
			(stroke
				(width 0.1)
				(type default)
			)
			(layer "F.Fab")
		)
		(fp_line
			(start 0.67945 -0.3048)
			(end 0.67945 0.3048)
			(stroke
				(width 0.1)
				(type default)
			)
			(layer "F.Fab")
		)
		(fp_line
			(start 0.12065 -0.3048)
			(end 0.67945 -0.3048)
			(stroke
				(width 0.1)
				(type default)
			)
			(layer "F.Fab")
		)
		(fp_line
			(start 0.12065 -0.2794)
			(end 0.12065 -0.3048)
			(stroke
				(width 0.1)
				(type default)
			)
			(layer "F.Fab")
		)
		(fp_line
			(start -0.12065 -0.2794)
			(end 0.12065 -0.2794)
			(stroke
				(width 0.1)
				(type default)
			)
			(layer "F.Fab")
		)
		(fp_line
			(start 0.120396 0.2794)
			(end -0.12065 0.2794)
			(stroke
				(width 0.1)
				(type default)
			)
			(layer "F.Fab")
		)
		(fp_line
			(start -0.12065 0.2794)
			(end -0.12065 0.3048)
			(stroke
				(width 0.1)
				(type default)
			)
			(layer "F.Fab")
		)
		(fp_line
			(start 0.67945 0.3048)
			(end 0.120396 0.3048)
			(stroke
				(width 0.1)
				(type default)
			)
			(layer "F.Fab")
		)
		(fp_line
			(start 0.120396 0.3048)
			(end 0.120396 0.2794)
			(stroke
				(width 0.1)
				(type default)
			)
			(layer "F.Fab")
		)
		(fp_line
			(start -0.12065 0.3048)
			(end -0.67945 0.3048)
			(stroke
				(width 0.1)
				(type default)
			)
			(layer "F.Fab")
		)
		(fp_line
			(start -0.67945 0.3048)
			(end -0.67945 -0.305054)
			(stroke
				(width 0.1)
				(type default)
			)
			(layer "F.Fab")
		)
		(pad "1" smd circle
			(at -0.40005 0 90)
			(size 0 0)
			(layers "F.Cu" "F.Mask" "F.Paste")
			(net "P3V3_AUX")
		)
		(pad "2" smd circle
			(at 0.40005 0 90)
			(size 0 0)
			(layers "F.Cu" "F.Mask" "F.Paste")
			(net "UART_BMC_5_TXD_BUF1_R")
		)
	)
	(footprint ""
		(layer "F.Cu")
		(at 85.1662 -75.1586)
		(property "Reference" "C155"
			(at 0 0 0)
			(layer "F.SilkS")
			(hide yes)
			(effects
				(font
					(size 1.27 1.27)
				)
			)
		)
		(property "Value" ""
			(at 0 0 0)
			(layer "F.Fab")
			(effects
				(font
					(size 1.27 1.27)
				)
			)
		)
		(duplicate_pad_numbers_are_jumpers no)
		(fp_line
			(start -0.7874 -0.4064)
			(end 0.7874 -0.4064)
			(stroke
				(width 0.1524)
				(type default)
			)
			(layer "F.SilkS")
		)
		(fp_line
			(start -0.7874 0.4064)
			(end -0.7874 -0.4064)
			(stroke
				(width 0.1524)
				(type default)
			)
			(layer "F.SilkS")
		)
		(fp_line
			(start 0.7874 -0.4064)
			(end 0.7874 0.4064)
			(stroke
				(width 0.1524)
				(type default)
			)
			(layer "F.SilkS")
		)
		(fp_line
			(start 0.7874 0.4064)
			(end -0.7874 0.4064)
			(stroke
				(width 0.1524)
				(type default)
			)
			(layer "F.SilkS")
		)
		(fp_line
			(start -0.67945 -0.305054)
			(end -0.12065 -0.305054)
			(stroke
				(width 0.1)
				(type default)
			)
			(layer "F.Fab")
		)
		(fp_line
			(start -0.67945 0.3048)
			(end -0.67945 -0.305054)
			(stroke
				(width 0.1)
				(type default)
			)
			(layer "F.Fab")
		)
		(fp_line
			(start -0.12065 -0.305054)
			(end -0.12065 -0.2794)
			(stroke
				(width 0.1)
				(type default)
			)
			(layer "F.Fab")
		)
		(fp_line
			(start -0.12065 -0.2794)
			(end 0.12065 -0.2794)
			(stroke
				(width 0.1)
				(type default)
			)
			(layer "F.Fab")
		)
		(fp_line
			(start -0.12065 0.2794)
			(end -0.12065 0.3048)
			(stroke
				(width 0.1)
				(type default)
			)
			(layer "F.Fab")
		)
		(fp_line
			(start -0.12065 0.3048)
			(end -0.67945 0.3048)
			(stroke
				(width 0.1)
				(type default)
			)
			(layer "F.Fab")
		)
		(fp_line
			(start 0.120396 0.2794)
			(end -0.12065 0.2794)
			(stroke
				(width 0.1)
				(type default)
			)
			(layer "F.Fab")
		)
		(fp_line
			(start 0.120396 0.3048)
			(end 0.120396 0.2794)
			(stroke
				(width 0.1)
				(type default)
			)
			(layer "F.Fab")
		)
		(fp_line
			(start 0.12065 -0.3048)
			(end 0.67945 -0.3048)
			(stroke
				(width 0.1)
				(type default)
			)
			(layer "F.Fab")
		)
		(fp_line
			(start 0.12065 -0.2794)
			(end 0.12065 -0.3048)
			(stroke
				(width 0.1)
				(type default)
			)
			(layer "F.Fab")
		)
		(fp_line
			(start 0.67945 -0.3048)
			(end 0.67945 0.3048)
			(stroke
				(width 0.1)
				(type default)
			)
			(layer "F.Fab")
		)
		(fp_line
			(start 0.67945 0.3048)
			(end 0.120396 0.3048)
			(stroke
				(width 0.1)
				(type default)
			)
			(layer "F.Fab")
		)
		(pad "1" smd circle
			(at -0.40005 0)
			(size 0 0)
			(layers "F.Cu" "F.Mask" "F.Paste")
			(net "PWRGD_P1V2_AUX_R")
		)
		(pad "2" smd circle
			(at 0.40005 0)
			(size 0 0)
			(layers "F.Cu" "F.Mask" "F.Paste")
			(net "GND")
		)
	)
)
